(kicad_pcb
	(version 20260206)
	(generator "pcbnew")
	(generator_version "10.0")
	(general
		(thickness 1.6)
		(legacy_teardrops no)
	)
	(paper "A4")
	(title_block
		(title "04192023_DAF0TMB3IC0_F0TG_MB_C_brd_V02_OCP.brd")
		(comment 1 "Grand Teton / footprints 584-589 of 8354")
	)
	(layers
		(0 "F.Cu" signal "TOP")
		(4 "In1.Cu" signal "GND")
		(6 "In2.Cu" signal "IN1")
		(8 "In3.Cu" signal "GND1")
		(10 "In4.Cu" signal "IN2")
		(12 "In5.Cu" signal "GND2")
		(14 "In6.Cu" signal "IN3")
		(16 "In7.Cu" signal "GND3")
		(18 "In8.Cu" signal "VCC")
		(20 "In9.Cu" signal "VCC1")
		(22 "In10.Cu" signal "GND4")
		(24 "In11.Cu" signal "IN4")
		(26 "In12.Cu" signal "GND5")
		(28 "In13.Cu" signal "IN5")
		(30 "In14.Cu" signal "GND6")
		(32 "In15.Cu" signal "IN6")
		(34 "In16.Cu" signal "GND7")
		(2 "B.Cu" signal "BOTTOM")
		(9 "F.Adhes" user "F.Adhesive")
		(11 "B.Adhes" user "B.Adhesive")
		(13 "F.Paste" user "Package Geometry/Pastemask Top")
		(15 "B.Paste" user "Package Geometry/Pastemask Bottom")
		(5 "F.SilkS" user "Ref Des/Silkscreen Top")
		(7 "B.SilkS" user "Ref Des/Silkscreen Bottom")
		(1 "F.Mask" user "Board Geometry/Soldermask Top")
		(3 "B.Mask" user "Board Geometry/Soldermask Bottom")
		(17 "Dwgs.User" user "User.Drawings")
		(19 "Cmts.User" user "User.Comments")
		(21 "Eco1.User" user "User.Eco1")
		(23 "Eco2.User" user "User.Eco2")
		(25 "Edge.Cuts" user "Board Geometry/Outline")
		(27 "Margin" user)
		(31 "F.CrtYd" user "Package Geometry/Place Bound Top")
		(29 "B.CrtYd" user "Package Geometry/Place Bound Bottom")
		(35 "F.Fab" user "Ref Des/Assembly Top")
		(33 "B.Fab" user "Ref Des/Assembly Bottom")
	)
	(footprint ""
		(layer "F.Cu")
		(at 463.370168 -109.646212 180)
		(property "Reference" "R577"
			(at 0 0 180)
			(layer "F.SilkS")
			(hide yes)
			(effects
				(font
					(size 1.27 1.27)
				)
			)
		)
		(property "Value" ""
			(at 0 0 180)
			(layer "F.Fab")
			(effects
				(font
					(size 1.27 1.27)
				)
			)
		)
		(duplicate_pad_numbers_are_jumpers no)
		(fp_line
			(start 0.7874 0.4064)
			(end -0.7874 0.4064)
			(stroke
				(width 0.1524)
				(type default)
			)
			(layer "F.SilkS")
		)
		(fp_line
			(start 0.7874 -0.4064)
			(end 0.7874 0.4064)
			(stroke
				(width 0.1524)
				(type default)
			)
			(layer "F.SilkS")
		)
		(fp_line
			(start -0.7874 0.4064)
			(end -0.7874 -0.4064)
			(stroke
				(width 0.1524)
				(type default)
			)
			(layer "F.SilkS")
		)
		(fp_line
			(start -0.7874 -0.4064)
			(end 0.7874 -0.4064)
			(stroke
				(width 0.1524)
				(type default)
			)
			(layer "F.SilkS")
		)
		(fp_line
			(start 0.67945 0.3048)
			(end 0.120396 0.3048)
			(stroke
				(width 0.1)
				(type default)
			)
			(layer "F.Fab")
		)
		(fp_line
			(start 0.67945 -0.3048)
			(end 0.67945 0.3048)
			(stroke
				(width 0.1)
				(type default)
			)
			(layer "F.Fab")
		)
		(fp_line
			(start 0.12065 -0.2794)
			(end 0.12065 -0.3048)
			(stroke
				(width 0.1)
				(type default)
			)
			(layer "F.Fab")
		)
		(fp_line
			(start 0.12065 -0.3048)
			(end 0.67945 -0.3048)
			(stroke
				(width 0.1)
				(type default)
			)
			(layer "F.Fab")
		)
		(fp_line
			(start 0.120396 0.3048)
			(end 0.120396 0.2794)
			(stroke
				(width 0.1)
				(type default)
			)
			(layer "F.Fab")
		)
		(fp_line
			(start 0.120396 0.2794)
			(end -0.12065 0.2794)
			(stroke
				(width 0.1)
				(type default)
			)
			(layer "F.Fab")
		)
		(fp_line
			(start -0.12065 0.3048)
			(end -0.67945 0.3048)
			(stroke
				(width 0.1)
				(type default)
			)
			(layer "F.Fab")
		)
		(fp_line
			(start -0.12065 0.2794)
			(end -0.12065 0.3048)
			(stroke
				(width 0.1)
				(type default)
			)
			(layer "F.Fab")
		)
		(fp_line
			(start -0.12065 -0.2794)
			(end 0.12065 -0.2794)
			(stroke
				(width 0.1)
				(type default)
			)
			(layer "F.Fab")
		)
		(fp_line
			(start -0.12065 -0.305054)
			(end -0.12065 -0.2794)
			(stroke
				(width 0.1)
				(type default)
			)
			(layer "F.Fab")
		)
		(fp_line
			(start -0.67945 0.3048)
			(end -0.67945 -0.305054)
			(stroke
				(width 0.1)
				(type default)
			)
			(layer "F.Fab")
		)
		(fp_line
			(start -0.67945 -0.305054)
			(end -0.12065 -0.305054)
			(stroke
				(width 0.1)
				(type default)
			)
			(layer "F.Fab")
		)
		(pad "1" smd circle
			(at -0.40005 0 180)
			(size 0 0)
			(layers "F.Cu" "F.Mask" "F.Paste")
			(net "P3V3_AUX")
		)
		(pad "2" smd circle
			(at 0.40005 0 180)
			(size 0 0)
			(layers "F.Cu" "F.Mask" "F.Paste")
			(net "HP_LVC3_OCP_SFF_PRSNT2_N")
		)
	)
	(footprint ""
		(layer "F.Cu")
		(at 253.506224 -133.622796 180)
		(property "Reference" "R600"
			(at 0 0 180)
			(layer "F.SilkS")
			(hide yes)
			(effects
				(font
					(size 1.27 1.27)
				)
			)
		)
		(property "Value" ""
			(at 0 0 180)
			(layer "F.Fab")
			(effects
				(font
					(size 1.27 1.27)
				)
			)
		)
		(duplicate_pad_numbers_are_jumpers no)
		(fp_line
			(start 0.7874 0.4064)
			(end -0.7874 0.4064)
			(stroke
				(width 0.1524)
				(type default)
			)
			(layer "F.SilkS")
		)
		(fp_line
			(start 0.7874 -0.4064)
			(end 0.7874 0.4064)
			(stroke
				(width 0.1524)
				(type default)
			)
			(layer "F.SilkS")
		)
		(fp_line
			(start -0.7874 0.4064)
			(end -0.7874 -0.4064)
			(stroke
				(width 0.1524)
				(type default)
			)
			(layer "F.SilkS")
		)
		(fp_line
			(start -0.7874 -0.4064)
			(end 0.7874 -0.4064)
			(stroke
				(width 0.1524)
				(type default)
			)
			(layer "F.SilkS")
		)
		(fp_line
			(start 0.67945 0.3048)
			(end 0.120396 0.3048)
			(stroke
				(width 0.1)
				(type default)
			)
			(layer "F.Fab")
		)
		(fp_line
			(start 0.67945 -0.3048)
			(end 0.67945 0.3048)
			(stroke
				(width 0.1)
				(type default)
			)
			(layer "F.Fab")
		)
		(fp_line
			(start 0.12065 -0.2794)
			(end 0.12065 -0.3048)
			(stroke
				(width 0.1)
				(type default)
			)
			(layer "F.Fab")
		)
		(fp_line
			(start 0.12065 -0.3048)
			(end 0.67945 -0.3048)
			(stroke
				(width 0.1)
				(type default)
			)
			(layer "F.Fab")
		)
		(fp_line
			(start 0.120396 0.3048)
			(end 0.120396 0.2794)
			(stroke
				(width 0.1)
				(type default)
			)
			(layer "F.Fab")
		)
		(fp_line
			(start 0.120396 0.2794)
			(end -0.12065 0.2794)
			(stroke
				(width 0.1)
				(type default)
			)
			(layer "F.Fab")
		)
		(fp_line
			(start -0.12065 0.3048)
			(end -0.67945 0.3048)
			(stroke
				(width 0.1)
				(type default)
			)
			(layer "F.Fab")
		)
		(fp_line
			(start -0.12065 0.2794)
			(end -0.12065 0.3048)
			(stroke
				(width 0.1)
				(type default)
			)
			(layer "F.Fab")
		)
		(fp_line
			(start -0.12065 -0.2794)
			(end 0.12065 -0.2794)
			(stroke
				(width 0.1)
				(type default)
			)
			(layer "F.Fab")
		)
		(fp_line
			(start -0.12065 -0.305054)
			(end -0.12065 -0.2794)
			(stroke
				(width 0.1)
				(type default)
			)
			(layer "F.Fab")
		)
		(fp_line
			(start -0.67945 0.3048)
			(end -0.67945 -0.305054)
			(stroke
				(width 0.1)
				(type default)
			)
			(layer "F.Fab")
		)
		(fp_line
			(start -0.67945 -0.305054)
			(end -0.12065 -0.305054)
			(stroke
				(width 0.1)
				(type default)
			)
			(layer "F.Fab")
		)
		(pad "1" smd circle
			(at -0.40005 0 180)
			(size 0 0)
			(layers "F.Cu" "F.Mask" "F.Paste")
			(net "SPI_CPU0_LVC3_CS1_N")
		)
		(pad "2" smd circle
			(at 0.40005 0 180)
			(size 0 0)
			(layers "F.Cu" "F.Mask" "F.Paste")
			(net "SPI_CPU0_LVC3_SCM_CS1_N")
		)
	)
	(footprint ""
		(layer "F.Cu")
		(at 102.021386 -386.44068 90)
		(property "Reference" "C111"
			(at 0 0 90)
			(layer "F.SilkS")
			(hide yes)
			(effects
				(font
					(size 1.27 1.27)
				)
			)
		)
		(property "Value" ""
			(at 0 0 90)
			(layer "F.Fab")
			(effects
				(font
					(size 1.27 1.27)
				)
			)
		)
		(duplicate_pad_numbers_are_jumpers no)
		(fp_line
			(start 0.7874 -0.4064)
			(end 0.7874 0.4064)
			(stroke
				(width 0.1524)
				(type default)
			)
			(layer "F.SilkS")
		)
		(fp_line
			(start -0.7874 -0.4064)
			(end 0.7874 -0.4064)
			(stroke
				(width 0.1524)
				(type default)
			)
			(layer "F.SilkS")
		)
		(fp_line
			(start 0.7874 0.4064)
			(end -0.7874 0.4064)
			(stroke
				(width 0.1524)
				(type default)
			)
			(layer "F.SilkS")
		)
		(fp_line
			(start -0.7874 0.4064)
			(end -0.7874 -0.4064)
			(stroke
				(width 0.1524)
				(type default)
			)
			(layer "F.SilkS")
		)
		(fp_line
			(start -0.12065 -0.305054)
			(end -0.12065 -0.2794)
			(stroke
				(width 0.1)
				(type default)
			)
			(layer "F.Fab")
		)
		(fp_line
			(start -0.67945 -0.305054)
			(end -0.12065 -0.305054)
			(stroke
				(width 0.1)
				(type default)
			)
			(layer "F.Fab")
		)
		(fp_line
			(start 0.67945 -0.3048)
			(end 0.67945 0.3048)
			(stroke
				(width 0.1)
				(type default)
			)
			(layer "F.Fab")
		)
		(fp_line
			(start 0.12065 -0.3048)
			(end 0.67945 -0.3048)
			(stroke
				(width 0.1)
				(type default)
			)
			(layer "F.Fab")
		)
		(fp_line
			(start 0.12065 -0.2794)
			(end 0.12065 -0.3048)
			(stroke
				(width 0.1)
				(type default)
			)
			(layer "F.Fab")
		)
		(fp_line
			(start -0.12065 -0.2794)
			(end 0.12065 -0.2794)
			(stroke
				(width 0.1)
				(type default)
			)
			(layer "F.Fab")
		)
		(fp_line
			(start 0.120396 0.2794)
			(end -0.12065 0.2794)
			(stroke
				(width 0.1)
				(type default)
			)
			(layer "F.Fab")
		)
		(fp_line
			(start -0.12065 0.2794)
			(end -0.12065 0.3048)
			(stroke
				(width 0.1)
				(type default)
			)
			(layer "F.Fab")
		)
		(fp_line
			(start 0.67945 0.3048)
			(end 0.120396 0.3048)
			(stroke
				(width 0.1)
				(type default)
			)
			(layer "F.Fab")
		)
		(fp_line
			(start 0.120396 0.3048)
			(end 0.120396 0.2794)
			(stroke
				(width 0.1)
				(type default)
			)
			(layer "F.Fab")
		)
		(fp_line
			(start -0.12065 0.3048)
			(end -0.67945 0.3048)
			(stroke
				(width 0.1)
				(type default)
			)
			(layer "F.Fab")
		)
		(fp_line
			(start -0.67945 0.3048)
			(end -0.67945 -0.305054)
			(stroke
				(width 0.1)
				(type default)
			)
			(layer "F.Fab")
		)
		(pad "1" smd circle
			(at -0.40005 0 90)
			(size 0 0)
			(layers "F.Cu" "F.Mask" "F.Paste")
			(net "P1V8_CPU1_RT1_1A")
		)
		(pad "2" smd circle
			(at 0.40005 0 90)
			(size 0 0)
			(layers "F.Cu" "F.Mask" "F.Paste")
			(net "GND")
		)
	)
	(footprint ""
		(layer "F.Cu")
		(at 255.447546 -43.902122 90)
		(property "Reference" "PC2209"
			(at 0 0 90)
			(layer "F.SilkS")
			(hide yes)
			(effects
				(font
					(size 1.27 1.27)
				)
			)
		)
		(property "Value" ""
			(at 0 0 90)
			(layer "F.Fab")
			(effects
				(font
					(size 1.27 1.27)
				)
			)
		)
		(duplicate_pad_numbers_are_jumpers no)
		(fp_line
			(start 0.7874 -0.4064)
			(end 0.7874 0.4064)
			(stroke
				(width 0.1524)
				(type default)
			)
			(layer "F.SilkS")
		)
		(fp_line
			(start -0.7874 -0.4064)
			(end 0.7874 -0.4064)
			(stroke
				(width 0.1524)
				(type default)
			)
			(layer "F.SilkS")
		)
		(fp_line
			(start 0.7874 0.4064)
			(end -0.7874 0.4064)
			(stroke
				(width 0.1524)
				(type default)
			)
			(layer "F.SilkS")
		)
		(fp_line
			(start -0.7874 0.4064)
			(end -0.7874 -0.4064)
			(stroke
				(width 0.1524)
				(type default)
			)
			(layer "F.SilkS")
		)
		(fp_line
			(start -0.12065 -0.305054)
			(end -0.12065 -0.2794)
			(stroke
				(width 0.1)
				(type default)
			)
			(layer "F.Fab")
		)
		(fp_line
			(start -0.67945 -0.305054)
			(end -0.12065 -0.305054)
			(stroke
				(width 0.1)
				(type default)
			)
			(layer "F.Fab")
		)
		(fp_line
			(start 0.67945 -0.3048)
			(end 0.67945 0.3048)
			(stroke
				(width 0.1)
				(type default)
			)
			(layer "F.Fab")
		)
		(fp_line
			(start 0.12065 -0.3048)
			(end 0.67945 -0.3048)
			(stroke
				(width 0.1)
				(type default)
			)
			(layer "F.Fab")
		)
		(fp_line
			(start 0.12065 -0.2794)
			(end 0.12065 -0.3048)
			(stroke
				(width 0.1)
				(type default)
			)
			(layer "F.Fab")
		)
		(fp_line
			(start -0.12065 -0.2794)
			(end 0.12065 -0.2794)
			(stroke
				(width 0.1)
				(type default)
			)
			(layer "F.Fab")
		)
		(fp_line
			(start 0.120396 0.2794)
			(end -0.12065 0.2794)
			(stroke
				(width 0.1)
				(type default)
			)
			(layer "F.Fab")
		)
		(fp_line
			(start -0.12065 0.2794)
			(end -0.12065 0.3048)
			(stroke
				(width 0.1)
				(type default)
			)
			(layer "F.Fab")
		)
		(fp_line
			(start 0.67945 0.3048)
			(end 0.120396 0.3048)
			(stroke
				(width 0.1)
				(type default)
			)
			(layer "F.Fab")
		)
		(fp_line
			(start 0.120396 0.3048)
			(end 0.120396 0.2794)
			(stroke
				(width 0.1)
				(type default)
			)
			(layer "F.Fab")
		)
		(fp_line
			(start -0.12065 0.3048)
			(end -0.67945 0.3048)
			(stroke
				(width 0.1)
				(type default)
			)
			(layer "F.Fab")
		)
		(fp_line
			(start -0.67945 0.3048)
			(end -0.67945 -0.305054)
			(stroke
				(width 0.1)
				(type default)
			)
			(layer "F.Fab")
		)
		(pad "1" smd circle
			(at -0.40005 0 90)
			(size 0 0)
			(layers "F.Cu" "F.Mask" "F.Paste")
			(net "P12V_E1S_VCC_0")
		)
		(pad "2" smd circle
			(at 0.40005 0 90)
			(size 0 0)
			(layers "F.Cu" "F.Mask" "F.Paste")
			(net "GND")
		)
	)
	(footprint ""
		(layer "F.Cu")
		(at 205.214982 -123.785376)
		(property "Reference" "R2844"
			(at 0 0 0)
			(layer "F.SilkS")
			(hide yes)
			(effects
				(font
					(size 1.27 1.27)
				)
			)
		)
		(property "Value" ""
			(at 0 0 0)
			(layer "F.Fab")
			(effects
				(font
					(size 1.27 1.27)
				)
			)
		)
		(duplicate_pad_numbers_are_jumpers no)
		(fp_line
			(start -0.7874 -0.4064)
			(end 0.7874 -0.4064)
			(stroke
				(width 0.1524)
				(type default)
			)
			(layer "F.SilkS")
		)
		(fp_line
			(start -0.7874 0.4064)
			(end -0.7874 -0.4064)
			(stroke
				(width 0.1524)
				(type default)
			)
			(layer "F.SilkS")
		)
		(fp_line
			(start 0.7874 -0.4064)
			(end 0.7874 0.4064)
			(stroke
				(width 0.1524)
				(type default)
			)
			(layer "F.SilkS")
		)
		(fp_line
			(start 0.7874 0.4064)
			(end -0.7874 0.4064)
			(stroke
				(width 0.1524)
				(type default)
			)
			(layer "F.SilkS")
		)
		(fp_line
			(start -0.67945 -0.305054)
			(end -0.12065 -0.305054)
			(stroke
				(width 0.1)
				(type default)
			)
			(layer "F.Fab")
		)
		(fp_line
			(start -0.67945 0.3048)
			(end -0.67945 -0.305054)
			(stroke
				(width 0.1)
				(type default)
			)
			(layer "F.Fab")
		)
		(fp_line
			(start -0.12065 -0.305054)
			(end -0.12065 -0.2794)
			(stroke
				(width 0.1)
				(type default)
			)
			(layer "F.Fab")
		)
		(fp_line
			(start -0.12065 -0.2794)
			(end 0.12065 -0.2794)
			(stroke
				(width 0.1)
				(type default)
			)
			(layer "F.Fab")
		)
		(fp_line
			(start -0.12065 0.2794)
			(end -0.12065 0.3048)
			(stroke
				(width 0.1)
				(type default)
			)
			(layer "F.Fab")
		)
		(fp_line
			(start -0.12065 0.3048)
			(end -0.67945 0.3048)
			(stroke
				(width 0.1)
				(type default)
			)
			(layer "F.Fab")
		)
		(fp_line
			(start 0.120396 0.2794)
			(end -0.12065 0.2794)
			(stroke
				(width 0.1)
				(type default)
			)
			(layer "F.Fab")
		)
		(fp_line
			(start 0.120396 0.3048)
			(end 0.120396 0.2794)
			(stroke
				(width 0.1)
				(type default)
			)
			(layer "F.Fab")
		)
		(fp_line
			(start 0.12065 -0.3048)
			(end 0.67945 -0.3048)
			(stroke
				(width 0.1)
				(type default)
			)
			(layer "F.Fab")
		)
		(fp_line
			(start 0.12065 -0.2794)
			(end 0.12065 -0.3048)
			(stroke
				(width 0.1)
				(type default)
			)
			(layer "F.Fab")
		)
		(fp_line
			(start 0.67945 -0.3048)
			(end 0.67945 0.3048)
			(stroke
				(width 0.1)
				(type default)
			)
			(layer "F.Fab")
		)
		(fp_line
			(start 0.67945 0.3048)
			(end 0.120396 0.3048)
			(stroke
				(width 0.1)
				(type default)
			)
			(layer "F.Fab")
		)
		(pad "1" smd circle
			(at -0.40005 0)
			(size 0 0)
			(layers "F.Cu" "F.Mask" "F.Paste")
			(net "FM_SWB_BIC_READY_ISO_R_N")
		)
		(pad "2" smd circle
			(at 0.40005 0)
			(size 0 0)
			(layers "F.Cu" "F.Mask" "F.Paste")
			(net "FM_SWB_BIC_READY_ISO_N")
		)
	)
	(footprint ""
		(layer "F.Cu")
		(at 425.54144 -434.467508 90)
		(property "Reference" "R4164"
			(at 0 0 90)
			(layer "F.SilkS")
			(hide yes)
			(effects
				(font
					(size 1.27 1.27)
				)
			)
		)
		(property "Value" ""
			(at 0 0 90)
			(layer "F.Fab")
			(effects
				(font
					(size 1.27 1.27)
				)
			)
		)
		(duplicate_pad_numbers_are_jumpers no)
		(fp_line
			(start 0.7874 -0.4064)
			(end 0.7874 0.4064)
			(stroke
				(width 0.1524)
				(type default)
			)
			(layer "F.SilkS")
		)
		(fp_line
			(start -0.7874 -0.4064)
			(end 0.7874 -0.4064)
			(stroke
				(width 0.1524)
				(type default)
			)
			(layer "F.SilkS")
		)
		(fp_line
			(start 0.7874 0.4064)
			(end -0.7874 0.4064)
			(stroke
				(width 0.1524)
				(type default)
			)
			(layer "F.SilkS")
		)
		(fp_line
			(start -0.7874 0.4064)
			(end -0.7874 -0.4064)
			(stroke
				(width 0.1524)
				(type default)
			)
			(layer "F.SilkS")
		)
		(fp_line
			(start -0.12065 -0.305054)
			(end -0.12065 -0.2794)
			(stroke
				(width 0.1)
				(type default)
			)
			(layer "F.Fab")
		)
		(fp_line
			(start -0.67945 -0.305054)
			(end -0.12065 -0.305054)
			(stroke
				(width 0.1)
				(type default)
			)
			(layer "F.Fab")
		)
		(fp_line
			(start 0.67945 -0.3048)
			(end 0.67945 0.3048)
			(stroke
				(width 0.1)
				(type default)
			)
			(layer "F.Fab")
		)
		(fp_line
			(start 0.12065 -0.3048)
			(end 0.67945 -0.3048)
			(stroke
				(width 0.1)
				(type default)
			)
			(layer "F.Fab")
		)
		(fp_line
			(start 0.12065 -0.2794)
			(end 0.12065 -0.3048)
			(stroke
				(width 0.1)
				(type default)
			)
			(layer "F.Fab")
		)
		(fp_line
			(start -0.12065 -0.2794)
			(end 0.12065 -0.2794)
			(stroke
				(width 0.1)
				(type default)
			)
			(layer "F.Fab")
		)
		(fp_line
			(start 0.120396 0.2794)
			(end -0.12065 0.2794)
			(stroke
				(width 0.1)
				(type default)
			)
			(layer "F.Fab")
		)
		(fp_line
			(start -0.12065 0.2794)
			(end -0.12065 0.3048)
			(stroke
				(width 0.1)
				(type default)
			)
			(layer "F.Fab")
		)
		(fp_line
			(start 0.67945 0.3048)
			(end 0.120396 0.3048)
			(stroke
				(width 0.1)
				(type default)
			)
			(layer "F.Fab")
		)
		(fp_line
			(start 0.120396 0.3048)
			(end 0.120396 0.2794)
			(stroke
				(width 0.1)
				(type default)
			)
			(layer "F.Fab")
		)
		(fp_line
			(start -0.12065 0.3048)
			(end -0.67945 0.3048)
			(stroke
				(width 0.1)
				(type default)
			)
			(layer "F.Fab")
		)
		(fp_line
			(start -0.67945 0.3048)
			(end -0.67945 -0.305054)
			(stroke
				(width 0.1)
				(type default)
			)
			(layer "F.Fab")
		)
		(pad "1" smd circle
			(at -0.40005 0 90)
			(size 0 0)
			(layers "F.Cu" "F.Mask" "F.Paste")
			(net "P3V3_AUX")
		)
		(pad "2" smd circle
			(at 0.40005 0 90)
			(size 0 0)
			(layers "F.Cu" "F.Mask" "F.Paste")
			(net "GPU_3V3IO_RSVD1_N")
		)
	)
)
